(kicad_pcb
	(version 20260206)
	(generator "pcbnew")
	(generator_version "10.0")
	(general
		(thickness 1.6)
		(legacy_teardrops no)
	)
	(paper "A4")
	(title_block
		(title "04192023_DAF0TMB3IC0_F0TG_MB_C_brd_V02_OCP.brd")
		(comment 1 "Grand Teton / footprints 4168-4174 of 8354")
	)
	(layers
		(0 "F.Cu" signal "TOP")
		(4 "In1.Cu" signal "GND")
		(6 "In2.Cu" signal "IN1")
		(8 "In3.Cu" signal "GND1")
		(10 "In4.Cu" signal "IN2")
		(12 "In5.Cu" signal "GND2")
		(14 "In6.Cu" signal "IN3")
		(16 "In7.Cu" signal "GND3")
		(18 "In8.Cu" signal "VCC")
		(20 "In9.Cu" signal "VCC1")
		(22 "In10.Cu" signal "GND4")
		(24 "In11.Cu" signal "IN4")
		(26 "In12.Cu" signal "GND5")
		(28 "In13.Cu" signal "IN5")
		(30 "In14.Cu" signal "GND6")
		(32 "In15.Cu" signal "IN6")
		(34 "In16.Cu" signal "GND7")
		(2 "B.Cu" signal "BOTTOM")
		(9 "F.Adhes" user "F.Adhesive")
		(11 "B.Adhes" user "B.Adhesive")
		(13 "F.Paste" user "Package Geometry/Pastemask Top")
		(15 "B.Paste" user "Package Geometry/Pastemask Bottom")
		(5 "F.SilkS" user "Ref Des/Silkscreen Top")
		(7 "B.SilkS" user "Ref Des/Silkscreen Bottom")
		(1 "F.Mask" user "Board Geometry/Soldermask Top")
		(3 "B.Mask" user "Board Geometry/Soldermask Bottom")
		(17 "Dwgs.User" user "User.Drawings")
		(19 "Cmts.User" user "User.Comments")
		(21 "Eco1.User" user "User.Eco1")
		(23 "Eco2.User" user "User.Eco2")
		(25 "Edge.Cuts" user "Board Geometry/Outline")
		(27 "Margin" user)
		(31 "F.CrtYd" user "Package Geometry/Place Bound Top")
		(29 "B.CrtYd" user "Package Geometry/Place Bound Bottom")
		(35 "F.Fab" user "Ref Des/Assembly Top")
		(33 "B.Fab" user "Ref Des/Assembly Bottom")
	)
	(footprint ""
		(layer "F.Cu")
		(at 111.581946 -52.86248 -90)
		(property "Reference" "R6305"
			(at 0 0 270)
			(layer "F.SilkS")
			(hide yes)
			(effects
				(font
					(size 1.27 1.27)
				)
			)
		)
		(property "Value" ""
			(at 0 0 270)
			(layer "F.Fab")
			(effects
				(font
					(size 1.27 1.27)
				)
			)
		)
		(duplicate_pad_numbers_are_jumpers no)
		(fp_line
			(start -0.7874 0.4064)
			(end -0.7874 -0.4064)
			(stroke
				(width 0.1524)
				(type default)
			)
			(layer "F.SilkS")
		)
		(fp_line
			(start 0.7874 0.4064)
			(end -0.7874 0.4064)
			(stroke
				(width 0.1524)
				(type default)
			)
			(layer "F.SilkS")
		)
		(fp_line
			(start -0.7874 -0.4064)
			(end 0.7874 -0.4064)
			(stroke
				(width 0.1524)
				(type default)
			)
			(layer "F.SilkS")
		)
		(fp_line
			(start 0.7874 -0.4064)
			(end 0.7874 0.4064)
			(stroke
				(width 0.1524)
				(type default)
			)
			(layer "F.SilkS")
		)
		(fp_line
			(start -0.67945 0.3048)
			(end -0.67945 -0.305054)
			(stroke
				(width 0.1)
				(type default)
			)
			(layer "F.Fab")
		)
		(fp_line
			(start -0.12065 0.3048)
			(end -0.67945 0.3048)
			(stroke
				(width 0.1)
				(type default)
			)
			(layer "F.Fab")
		)
		(fp_line
			(start 0.120396 0.3048)
			(end 0.120396 0.2794)
			(stroke
				(width 0.1)
				(type default)
			)
			(layer "F.Fab")
		)
		(fp_line
			(start 0.67945 0.3048)
			(end 0.120396 0.3048)
			(stroke
				(width 0.1)
				(type default)
			)
			(layer "F.Fab")
		)
		(fp_line
			(start -0.12065 0.2794)
			(end -0.12065 0.3048)
			(stroke
				(width 0.1)
				(type default)
			)
			(layer "F.Fab")
		)
		(fp_line
			(start 0.120396 0.2794)
			(end -0.12065 0.2794)
			(stroke
				(width 0.1)
				(type default)
			)
			(layer "F.Fab")
		)
		(fp_line
			(start -0.12065 -0.2794)
			(end 0.12065 -0.2794)
			(stroke
				(width 0.1)
				(type default)
			)
			(layer "F.Fab")
		)
		(fp_line
			(start 0.12065 -0.2794)
			(end 0.12065 -0.3048)
			(stroke
				(width 0.1)
				(type default)
			)
			(layer "F.Fab")
		)
		(fp_line
			(start 0.12065 -0.3048)
			(end 0.67945 -0.3048)
			(stroke
				(width 0.1)
				(type default)
			)
			(layer "F.Fab")
		)
		(fp_line
			(start 0.67945 -0.3048)
			(end 0.67945 0.3048)
			(stroke
				(width 0.1)
				(type default)
			)
			(layer "F.Fab")
		)
		(fp_line
			(start -0.67945 -0.305054)
			(end -0.12065 -0.305054)
			(stroke
				(width 0.1)
				(type default)
			)
			(layer "F.Fab")
		)
		(fp_line
			(start -0.12065 -0.305054)
			(end -0.12065 -0.2794)
			(stroke
				(width 0.1)
				(type default)
			)
			(layer "F.Fab")
		)
		(pad "1" smd circle
			(at -0.40005 0 270)
			(size 0 0)
			(layers "F.Cu" "F.Mask" "F.Paste")
			(net "USB_HUB2_MRP_CFG_NON_REM")
		)
		(pad "2" smd circle
			(at 0.40005 0 270)
			(size 0 0)
			(layers "F.Cu" "F.Mask" "F.Paste")
			(net "USB_HUB2_TI_HS_SUSPEND_MRP_CFG_NON_REM")
		)
	)
	(footprint ""
		(layer "F.Cu")
		(at 60.57011 -351.932748)
		(property "Reference" "PR262"
			(at 0 0 0)
			(layer "F.SilkS")
			(hide yes)
			(effects
				(font
					(size 1.27 1.27)
				)
			)
		)
		(property "Value" ""
			(at 0 0 0)
			(layer "F.Fab")
			(effects
				(font
					(size 1.27 1.27)
				)
			)
		)
		(duplicate_pad_numbers_are_jumpers no)
		(fp_line
			(start -0.7874 -0.4064)
			(end 0.7874 -0.4064)
			(stroke
				(width 0.1524)
				(type default)
			)
			(layer "F.SilkS")
		)
		(fp_line
			(start -0.7874 0.4064)
			(end -0.7874 -0.4064)
			(stroke
				(width 0.1524)
				(type default)
			)
			(layer "F.SilkS")
		)
		(fp_line
			(start 0.7874 -0.4064)
			(end 0.7874 0.4064)
			(stroke
				(width 0.1524)
				(type default)
			)
			(layer "F.SilkS")
		)
		(fp_line
			(start 0.7874 0.4064)
			(end -0.7874 0.4064)
			(stroke
				(width 0.1524)
				(type default)
			)
			(layer "F.SilkS")
		)
		(fp_line
			(start -0.67945 -0.305054)
			(end -0.12065 -0.305054)
			(stroke
				(width 0.1)
				(type default)
			)
			(layer "F.Fab")
		)
		(fp_line
			(start -0.67945 0.3048)
			(end -0.67945 -0.305054)
			(stroke
				(width 0.1)
				(type default)
			)
			(layer "F.Fab")
		)
		(fp_line
			(start -0.12065 -0.305054)
			(end -0.12065 -0.2794)
			(stroke
				(width 0.1)
				(type default)
			)
			(layer "F.Fab")
		)
		(fp_line
			(start -0.12065 -0.2794)
			(end 0.12065 -0.2794)
			(stroke
				(width 0.1)
				(type default)
			)
			(layer "F.Fab")
		)
		(fp_line
			(start -0.12065 0.2794)
			(end -0.12065 0.3048)
			(stroke
				(width 0.1)
				(type default)
			)
			(layer "F.Fab")
		)
		(fp_line
			(start -0.12065 0.3048)
			(end -0.67945 0.3048)
			(stroke
				(width 0.1)
				(type default)
			)
			(layer "F.Fab")
		)
		(fp_line
			(start 0.120396 0.2794)
			(end -0.12065 0.2794)
			(stroke
				(width 0.1)
				(type default)
			)
			(layer "F.Fab")
		)
		(fp_line
			(start 0.120396 0.3048)
			(end 0.120396 0.2794)
			(stroke
				(width 0.1)
				(type default)
			)
			(layer "F.Fab")
		)
		(fp_line
			(start 0.12065 -0.3048)
			(end 0.67945 -0.3048)
			(stroke
				(width 0.1)
				(type default)
			)
			(layer "F.Fab")
		)
		(fp_line
			(start 0.12065 -0.2794)
			(end 0.12065 -0.3048)
			(stroke
				(width 0.1)
				(type default)
			)
			(layer "F.Fab")
		)
		(fp_line
			(start 0.67945 -0.3048)
			(end 0.67945 0.3048)
			(stroke
				(width 0.1)
				(type default)
			)
			(layer "F.Fab")
		)
		(fp_line
			(start 0.67945 0.3048)
			(end 0.120396 0.3048)
			(stroke
				(width 0.1)
				(type default)
			)
			(layer "F.Fab")
		)
		(pad "1" smd circle
			(at -0.40005 0)
			(size 0 0)
			(layers "F.Cu" "F.Mask" "F.Paste")
			(net "PVDDCR_CPU1_P1_LSET4")
		)
		(pad "2" smd circle
			(at 0.40005 0)
			(size 0 0)
			(layers "F.Cu" "F.Mask" "F.Paste")
			(net "GND")
		)
	)
	(footprint ""
		(layer "F.Cu")
		(at 104.47528 -394.7668 -90)
		(property "Reference" "R671"
			(at 0 0 270)
			(layer "F.SilkS")
			(hide yes)
			(effects
				(font
					(size 1.27 1.27)
				)
			)
		)
		(property "Value" ""
			(at 0 0 270)
			(layer "F.Fab")
			(effects
				(font
					(size 1.27 1.27)
				)
			)
		)
		(duplicate_pad_numbers_are_jumpers no)
		(fp_line
			(start -0.32512 0.175006)
			(end -0.32512 -0.175006)
			(stroke
				(width 0.1)
				(type default)
			)
			(layer "F.Fab")
		)
		(fp_line
			(start 0.32512 0.175006)
			(end -0.32512 0.175006)
			(stroke
				(width 0.1)
				(type default)
			)
			(layer "F.Fab")
		)
		(fp_line
			(start -0.32512 -0.175006)
			(end 0.32512 -0.175006)
			(stroke
				(width 0.1)
				(type default)
			)
			(layer "F.Fab")
		)
		(fp_line
			(start 0.32512 -0.175006)
			(end 0.32512 0.175006)
			(stroke
				(width 0.1)
				(type default)
			)
			(layer "F.Fab")
		)
		(pad "1" smd rect
			(at -0.2667 0 270)
			(size 0.3048 0.381)
			(layers "F.Cu" "F.Mask" "F.Paste")
			(net "SMB_RT_CPU1_P1_ROM_MUX_1D_SDA")
		)
		(pad "2" smd rect
			(at 0.2667 0 90)
			(size 0.3048 0.381)
			(layers "F.Cu" "F.Mask" "F.Paste")
			(net "SMB_RT_CPU1_P1_ROM_MUX_1D_R_SDA")
		)
	)
	(footprint ""
		(layer "F.Cu")
		(at 191.29629 -30.269688 180)
		(property "Reference" "PR4526"
			(at 0 0 180)
			(layer "F.SilkS")
			(hide yes)
			(effects
				(font
					(size 1.27 1.27)
				)
			)
		)
		(property "Value" ""
			(at 0 0 180)
			(layer "F.Fab")
			(effects
				(font
					(size 1.27 1.27)
				)
			)
		)
		(duplicate_pad_numbers_are_jumpers no)
		(fp_line
			(start 0.7874 0.4064)
			(end -0.7874 0.4064)
			(stroke
				(width 0.1524)
				(type default)
			)
			(layer "F.SilkS")
		)
		(fp_line
			(start 0.7874 -0.4064)
			(end 0.7874 0.4064)
			(stroke
				(width 0.1524)
				(type default)
			)
			(layer "F.SilkS")
		)
		(fp_line
			(start -0.7874 0.4064)
			(end -0.7874 -0.4064)
			(stroke
				(width 0.1524)
				(type default)
			)
			(layer "F.SilkS")
		)
		(fp_line
			(start -0.7874 -0.4064)
			(end 0.7874 -0.4064)
			(stroke
				(width 0.1524)
				(type default)
			)
			(layer "F.SilkS")
		)
		(fp_line
			(start 0.67945 0.3048)
			(end 0.120396 0.3048)
			(stroke
				(width 0.1)
				(type default)
			)
			(layer "F.Fab")
		)
		(fp_line
			(start 0.67945 -0.3048)
			(end 0.67945 0.3048)
			(stroke
				(width 0.1)
				(type default)
			)
			(layer "F.Fab")
		)
		(fp_line
			(start 0.12065 -0.2794)
			(end 0.12065 -0.3048)
			(stroke
				(width 0.1)
				(type default)
			)
			(layer "F.Fab")
		)
		(fp_line
			(start 0.12065 -0.3048)
			(end 0.67945 -0.3048)
			(stroke
				(width 0.1)
				(type default)
			)
			(layer "F.Fab")
		)
		(fp_line
			(start 0.120396 0.3048)
			(end 0.120396 0.2794)
			(stroke
				(width 0.1)
				(type default)
			)
			(layer "F.Fab")
		)
		(fp_line
			(start 0.120396 0.2794)
			(end -0.12065 0.2794)
			(stroke
				(width 0.1)
				(type default)
			)
			(layer "F.Fab")
		)
		(fp_line
			(start -0.12065 0.3048)
			(end -0.67945 0.3048)
			(stroke
				(width 0.1)
				(type default)
			)
			(layer "F.Fab")
		)
		(fp_line
			(start -0.12065 0.2794)
			(end -0.12065 0.3048)
			(stroke
				(width 0.1)
				(type default)
			)
			(layer "F.Fab")
		)
		(fp_line
			(start -0.12065 -0.2794)
			(end 0.12065 -0.2794)
			(stroke
				(width 0.1)
				(type default)
			)
			(layer "F.Fab")
		)
		(fp_line
			(start -0.12065 -0.305054)
			(end -0.12065 -0.2794)
			(stroke
				(width 0.1)
				(type default)
			)
			(layer "F.Fab")
		)
		(fp_line
			(start -0.67945 0.3048)
			(end -0.67945 -0.305054)
			(stroke
				(width 0.1)
				(type default)
			)
			(layer "F.Fab")
		)
		(fp_line
			(start -0.67945 -0.305054)
			(end -0.12065 -0.305054)
			(stroke
				(width 0.1)
				(type default)
			)
			(layer "F.Fab")
		)
		(pad "1" smd circle
			(at -0.40005 0 180)
			(size 0 0)
			(layers "F.Cu" "F.Mask" "F.Paste")
			(net "P12V_SCM_R")
		)
		(pad "2" smd circle
			(at 0.40005 0 180)
			(size 0 0)
			(layers "F.Cu" "F.Mask" "F.Paste")
			(net "P12V_SCM_GATE")
		)
	)
	(footprint ""
		(layer "F.Cu")
		(at 165.109144 -344.153998 -90)
		(property "Reference" "PR14"
			(at 0 0 270)
			(layer "F.SilkS")
			(hide yes)
			(effects
				(font
					(size 1.27 1.27)
				)
			)
		)
		(property "Value" ""
			(at 0 0 270)
			(layer "F.Fab")
			(effects
				(font
					(size 1.27 1.27)
				)
			)
		)
		(duplicate_pad_numbers_are_jumpers no)
		(fp_line
			(start -0.7874 0.4064)
			(end -0.7874 -0.4064)
			(stroke
				(width 0.1524)
				(type default)
			)
			(layer "F.SilkS")
		)
		(fp_line
			(start 0.7874 0.4064)
			(end -0.7874 0.4064)
			(stroke
				(width 0.1524)
				(type default)
			)
			(layer "F.SilkS")
		)
		(fp_line
			(start -0.7874 -0.4064)
			(end 0.7874 -0.4064)
			(stroke
				(width 0.1524)
				(type default)
			)
			(layer "F.SilkS")
		)
		(fp_line
			(start 0.7874 -0.4064)
			(end 0.7874 0.4064)
			(stroke
				(width 0.1524)
				(type default)
			)
			(layer "F.SilkS")
		)
		(fp_line
			(start -0.67945 0.3048)
			(end -0.67945 -0.305054)
			(stroke
				(width 0.1)
				(type default)
			)
			(layer "F.Fab")
		)
		(fp_line
			(start -0.12065 0.3048)
			(end -0.67945 0.3048)
			(stroke
				(width 0.1)
				(type default)
			)
			(layer "F.Fab")
		)
		(fp_line
			(start 0.120396 0.3048)
			(end 0.120396 0.2794)
			(stroke
				(width 0.1)
				(type default)
			)
			(layer "F.Fab")
		)
		(fp_line
			(start 0.67945 0.3048)
			(end 0.120396 0.3048)
			(stroke
				(width 0.1)
				(type default)
			)
			(layer "F.Fab")
		)
		(fp_line
			(start -0.12065 0.2794)
			(end -0.12065 0.3048)
			(stroke
				(width 0.1)
				(type default)
			)
			(layer "F.Fab")
		)
		(fp_line
			(start 0.120396 0.2794)
			(end -0.12065 0.2794)
			(stroke
				(width 0.1)
				(type default)
			)
			(layer "F.Fab")
		)
		(fp_line
			(start -0.12065 -0.2794)
			(end 0.12065 -0.2794)
			(stroke
				(width 0.1)
				(type default)
			)
			(layer "F.Fab")
		)
		(fp_line
			(start 0.12065 -0.2794)
			(end 0.12065 -0.3048)
			(stroke
				(width 0.1)
				(type default)
			)
			(layer "F.Fab")
		)
		(fp_line
			(start 0.12065 -0.3048)
			(end 0.67945 -0.3048)
			(stroke
				(width 0.1)
				(type default)
			)
			(layer "F.Fab")
		)
		(fp_line
			(start 0.67945 -0.3048)
			(end 0.67945 0.3048)
			(stroke
				(width 0.1)
				(type default)
			)
			(layer "F.Fab")
		)
		(fp_line
			(start -0.67945 -0.305054)
			(end -0.12065 -0.305054)
			(stroke
				(width 0.1)
				(type default)
			)
			(layer "F.Fab")
		)
		(fp_line
			(start -0.12065 -0.305054)
			(end -0.12065 -0.2794)
			(stroke
				(width 0.1)
				(type default)
			)
			(layer "F.Fab")
		)
		(pad "1" smd circle
			(at -0.40005 0 270)
			(size 0 0)
			(layers "F.Cu" "F.Mask" "F.Paste")
			(net "NC_PVDD11_S3_P1_IMON6")
		)
		(pad "2" smd circle
			(at 0.40005 0 270)
			(size 0 0)
			(layers "F.Cu" "F.Mask" "F.Paste")
			(net "GND")
		)
	)
	(footprint ""
		(layer "F.Cu")
		(at 332.8924 -131.755642)
		(property "Reference" "PL77"
			(at 0 0 0)
			(layer "F.SilkS")
			(hide yes)
			(effects
				(font
					(size 1.27 1.27)
				)
			)
		)
		(property "Value" ""
			(at 0 0 0)
			(layer "F.Fab")
			(effects
				(font
					(size 1.27 1.27)
				)
			)
		)
		(duplicate_pad_numbers_are_jumpers no)
		(fp_line
			(start -1.27 -0.5842)
			(end 1.27 -0.5842)
			(stroke
				(width 0.1524)
				(type default)
			)
			(layer "F.SilkS")
		)
		(fp_line
			(start -1.27 -0.5588)
			(end -1.27 -0.5842)
			(stroke
				(width 0.1524)
				(type default)
			)
			(layer "F.SilkS")
		)
		(fp_line
			(start -1.27 0.5842)
			(end -1.27 -0.5842)
			(stroke
				(width 0.1524)
				(type default)
			)
			(layer "F.SilkS")
		)
		(fp_line
			(start 1.27 0.5842)
			(end -1.27 0.5842)
			(stroke
				(width 0.1524)
				(type default)
			)
			(layer "F.SilkS")
		)
		(fp_line
			(start 1.27 0.5842)
			(end 1.27 -0.5842)
			(stroke
				(width 0.1524)
				(type default)
			)
			(layer "F.SilkS")
		)
		(fp_line
			(start -1.194308 -0.406654)
			(end -0.9144 -0.406654)
			(stroke
				(width 0.1)
				(type default)
			)
			(layer "F.Fab")
		)
		(fp_line
			(start -1.194308 0.406654)
			(end -1.194308 -0.406654)
			(stroke
				(width 0.1)
				(type default)
			)
			(layer "F.Fab")
		)
		(fp_line
			(start -0.9144 -0.508)
			(end 0.9144 -0.508)
			(stroke
				(width 0.1)
				(type default)
			)
			(layer "F.Fab")
		)
		(fp_line
			(start -0.9144 -0.406654)
			(end -0.9144 -0.508)
			(stroke
				(width 0.1)
				(type default)
			)
			(layer "F.Fab")
		)
		(fp_line
			(start -0.9144 0.406654)
			(end -1.194308 0.406654)
			(stroke
				(width 0.1)
				(type default)
			)
			(layer "F.Fab")
		)
		(fp_line
			(start -0.9144 0.508)
			(end -0.9144 0.406654)
			(stroke
				(width 0.1)
				(type default)
			)
			(layer "F.Fab")
		)
		(fp_line
			(start 0.9144 -0.508)
			(end 0.9144 -0.406654)
			(stroke
				(width 0.1)
				(type default)
			)
			(layer "F.Fab")
		)
		(fp_line
			(start 0.9144 -0.406654)
			(end 1.1938 -0.406654)
			(stroke
				(width 0.1)
				(type default)
			)
			(layer "F.Fab")
		)
		(fp_line
			(start 0.9144 0.4064)
			(end 0.9144 0.508)
			(stroke
				(width 0.1)
				(type default)
			)
			(layer "F.Fab")
		)
		(fp_line
			(start 0.9144 0.508)
			(end -0.9144 0.508)
			(stroke
				(width 0.1)
				(type default)
			)
			(layer "F.Fab")
		)
		(fp_line
			(start 1.1938 -0.406654)
			(end 1.1938 0.4064)
			(stroke
				(width 0.1)
				(type default)
			)
			(layer "F.Fab")
		)
		(fp_line
			(start 1.1938 0.4064)
			(end 0.9144 0.4064)
			(stroke
				(width 0.1)
				(type default)
			)
			(layer "F.Fab")
		)
		(pad "1" smd rect
			(at -0.7366 0 270)
			(size 0.7112 0.8128)
			(layers "F.Cu" "F.Mask" "F.Paste")
			(net "P12V_AUX")
		)
		(pad "2" smd rect
			(at 0.7366 0 270)
			(size 0.7112 0.8128)
			(layers "F.Cu" "F.Mask" "F.Paste")
			(net "SW_P12V_AUX_PVDD18_S5_P0_FLT")
		)
	)
	(footprint ""
		(layer "F.Cu")
		(at 415.586418 -365.881412 -90)
		(property "Reference" "R120"
			(at 0 0 270)
			(layer "F.SilkS")
			(hide yes)
			(effects
				(font
					(size 1.27 1.27)
				)
			)
		)
		(property "Value" ""
			(at 0 0 270)
			(layer "F.Fab")
			(effects
				(font
					(size 1.27 1.27)
				)
			)
		)
		(duplicate_pad_numbers_are_jumpers no)
		(fp_line
			(start -0.7874 0.4064)
			(end -0.7874 -0.4064)
			(stroke
				(width 0.1524)
				(type default)
			)
			(layer "F.SilkS")
		)
		(fp_line
			(start 0.7874 0.4064)
			(end -0.7874 0.4064)
			(stroke
				(width 0.1524)
				(type default)
			)
			(layer "F.SilkS")
		)
		(fp_line
			(start -0.7874 -0.4064)
			(end 0.7874 -0.4064)
			(stroke
				(width 0.1524)
				(type default)
			)
			(layer "F.SilkS")
		)
		(fp_line
			(start 0.7874 -0.4064)
			(end 0.7874 0.4064)
			(stroke
				(width 0.1524)
				(type default)
			)
			(layer "F.SilkS")
		)
		(fp_line
			(start -0.67945 0.3048)
			(end -0.67945 -0.305054)
			(stroke
				(width 0.1)
				(type default)
			)
			(layer "F.Fab")
		)
		(fp_line
			(start -0.12065 0.3048)
			(end -0.67945 0.3048)
			(stroke
				(width 0.1)
				(type default)
			)
			(layer "F.Fab")
		)
		(fp_line
			(start 0.120396 0.3048)
			(end 0.120396 0.2794)
			(stroke
				(width 0.1)
				(type default)
			)
			(layer "F.Fab")
		)
		(fp_line
			(start 0.67945 0.3048)
			(end 0.120396 0.3048)
			(stroke
				(width 0.1)
				(type default)
			)
			(layer "F.Fab")
		)
		(fp_line
			(start -0.12065 0.2794)
			(end -0.12065 0.3048)
			(stroke
				(width 0.1)
				(type default)
			)
			(layer "F.Fab")
		)
		(fp_line
			(start 0.120396 0.2794)
			(end -0.12065 0.2794)
			(stroke
				(width 0.1)
				(type default)
			)
			(layer "F.Fab")
		)
		(fp_line
			(start -0.12065 -0.2794)
			(end 0.12065 -0.2794)
			(stroke
				(width 0.1)
				(type default)
			)
			(layer "F.Fab")
		)
		(fp_line
			(start 0.12065 -0.2794)
			(end 0.12065 -0.3048)
			(stroke
				(width 0.1)
				(type default)
			)
			(layer "F.Fab")
		)
		(fp_line
			(start 0.12065 -0.3048)
			(end 0.67945 -0.3048)
			(stroke
				(width 0.1)
				(type default)
			)
			(layer "F.Fab")
		)
		(fp_line
			(start 0.67945 -0.3048)
			(end 0.67945 0.3048)
			(stroke
				(width 0.1)
				(type default)
			)
			(layer "F.Fab")
		)
		(fp_line
			(start -0.67945 -0.305054)
			(end -0.12065 -0.305054)
			(stroke
				(width 0.1)
				(type default)
			)
			(layer "F.Fab")
		)
		(fp_line
			(start -0.12065 -0.305054)
			(end -0.12065 -0.2794)
			(stroke
				(width 0.1)
				(type default)
			)
			(layer "F.Fab")
		)
		(pad "1" smd circle
			(at -0.40005 0 270)
			(size 0 0)
			(layers "F.Cu" "F.Mask" "F.Paste")
			(net "PVDD11_S3_P0_PMALERT")
		)
		(pad "2" smd circle
			(at 0.40005 0 270)
			(size 0 0)
			(layers "F.Cu" "F.Mask" "F.Paste")
			(net "PVDD11_S3_P0_PMALERT_R")
		)
	)
)
